# BASEBOARD_FAB2 (Tioga Pass) — schematic netlist excerpt (pin names and nets, part order shuffled) for the footprints in the layout excerpt that follows; sources: Cadence DE-HDL packaged netlist, KiCad conversion of Wiwynn_Tioga_Pass_MB.brd

C5G83  CAP_A  22.0UF 4V 20% X6S  pkg 0603V  page 243 : A = PVDDQ_GHJ ; B = GND
C1R28  CAP_A  0.1UF 16V 10% X7R  pkg 0402V  page 170 : A = P3V3_STBY ; B = GND
R7P17  RES  90.9 1% CHIP  pkg 0402  page 55 : A = A_CPU1_GHJ_RCOMP1 ; B = GND

(kicad_pcb
	(version 20260206)
	(generator "pcbnew")
	(generator_version "10.0")
	(general
		(thickness 1.6)
		(legacy_teardrops no)
	)
	(paper "A4")
	(title_block
		(title "Wiwynn_Tioga_Pass_MB.brd")
		(comment 1 "Tioga Pass / footprints 3194-3196 of 4770")
	)
	(layers
		(0 "F.Cu" signal "TOP")
		(4 "In1.Cu" signal "L2GND")
		(6 "In2.Cu" signal "L3")
		(8 "In3.Cu" signal "L4GND")
		(10 "In4.Cu" signal "L5")
		(12 "In5.Cu" signal "L6GND")
		(14 "In6.Cu" signal "L7VCC")
		(16 "In7.Cu" signal "L8VCC")
		(18 "In8.Cu" signal "L9GND")
		(20 "In9.Cu" signal "L10")
		(22 "In10.Cu" signal "L11GND")
		(24 "In11.Cu" signal "L12")
		(26 "In12.Cu" signal "L13GND")
		(2 "B.Cu" signal "BOTTOM")
		(9 "F.Adhes" user "F.Adhesive")
		(11 "B.Adhes" user "B.Adhesive")
		(13 "F.Paste" user "Package Geometry/Pastemask Top")
		(15 "B.Paste" user "Package Geometry/Pastemask Bottom")
		(5 "F.SilkS" user "Ref Des/Silkscreen Top")
		(7 "B.SilkS" user "Ref Des/Silkscreen Bottom")
		(1 "F.Mask" user "Board Geometry/Soldermask Top")
		(3 "B.Mask" user "Board Geometry/Soldermask Bottom")
		(17 "Dwgs.User" user "User.Drawings")
		(19 "Cmts.User" user "User.Comments")
		(21 "Eco1.User" user "User.Eco1")
		(23 "Eco2.User" user "User.Eco2")
		(25 "Edge.Cuts" user "Board Geometry/Outline")
		(27 "Margin" user)
		(31 "F.CrtYd" user "Package Geometry/Place Bound Top")
		(29 "B.CrtYd" user "Package Geometry/Place Bound Bottom")
		(35 "F.Fab" user "Ref Des/Assembly Top")
		(33 "B.Fab" user "Ref Des/Assembly Bottom")
	)
	(footprint ""
		(layer "B.Cu")
		(at 421.66032 -73.962514)
		(property "Reference" "C1R28"
			(at 0 0 0)
			(layer "B.SilkS")
			(hide yes)
			(effects
				(font
					(size 1.27 1.27)
				)
				(justify mirror)
			)
		)
		(property "Value" ""
			(at 0 0 0)
			(layer "B.Fab")
			(effects
				(font
					(size 1.27 1.27)
				)
				(justify mirror)
			)
		)
		(duplicate_pad_numbers_are_jumpers no)
		(fp_poly
			(pts
				(xy -0.3048 -0.1016) (xy -0.3048 0.9906) (xy 0.3048 0.9906) (xy 0.3048 -0.1016)
			)
			(stroke
				(width 0)
				(type default)
			)
			(fill no)
			(layer "B.CrtYd")
		)
		(fp_line
			(start -0.3048 -0.1016)
			(end 0.3048 -0.1016)
			(stroke
				(width 0.1)
				(type default)
			)
			(layer "B.Fab")
		)
		(fp_line
			(start -0.3048 0.9906)
			(end -0.3048 -0.1016)
			(stroke
				(width 0.1)
				(type default)
			)
			(layer "B.Fab")
		)
		(fp_line
			(start 0.3048 -0.1016)
			(end 0.3048 0.9906)
			(stroke
				(width 0.1)
				(type default)
			)
			(layer "B.Fab")
		)
		(fp_line
			(start 0.3048 0.9906)
			(end -0.3048 0.9906)
			(stroke
				(width 0.1)
				(type default)
			)
			(layer "B.Fab")
		)
		(pad "1" smd rect
			(at 0 0 180)
			(size 0.508 0.508)
			(layers "B.Cu" "B.Mask" "B.Paste")
			(net "P3V3_STBY")
		)
		(pad "2" smd rect
			(at 0 0.889 180)
			(size 0.508 0.508)
			(layers "B.Cu" "B.Mask" "B.Paste")
			(net "GND")
		)
		(zone
			(layer "B.Cu")
			(hatch none 0.5)
			(connect_pads
				(clearance 0)
			)
			(min_thickness 0.25)
			(keepout
				(tracks allowed)
				(vias not_allowed)
				(pads allowed)
				(copperpour not_allowed)
				(footprints allowed)
			)
			(placement
				(enabled no)
				(sheetname "")
			)
			(fill
				(thermal_gap 0.5)
				(thermal_bridge_width 0.5)
				(island_removal_mode 0)
			)
			(polygon
				(pts
					(xy 421.91432 -73.708514) (xy 421.40632 -73.708514) (xy 421.40632 -73.327514) (xy 421.91432 -73.327514)
				)
			)
		)
		(zone
			(layer "B.Cu")
			(hatch none 0.5)
			(connect_pads
				(clearance 0)
			)
			(min_thickness 0.25)
			(keepout
				(tracks not_allowed)
				(vias allowed)
				(pads allowed)
				(copperpour not_allowed)
				(footprints allowed)
			)
			(placement
				(enabled no)
				(sheetname "")
			)
			(fill
				(thermal_gap 0.5)
				(thermal_bridge_width 0.5)
				(island_removal_mode 0)
			)
			(polygon
				(pts
					(xy 421.91432 -73.327514) (xy 421.40632 -73.327514) (xy 421.40632 -73.708514) (xy 421.91432 -73.708514)
				)
			)
		)
	)
	(footprint ""
		(layer "B.Cu")
		(at 117.1956 -72.644 -90)
		(property "Reference" "R7P17"
			(at 0 0 90)
			(layer "B.SilkS")
			(hide yes)
			(effects
				(font
					(size 1.27 1.27)
				)
				(justify mirror)
			)
		)
		(property "Value" ""
			(at 0 0 90)
			(layer "B.Fab")
			(effects
				(font
					(size 1.27 1.27)
				)
				(justify mirror)
			)
		)
		(duplicate_pad_numbers_are_jumpers no)
		(fp_poly
			(pts
				(xy 0.2794 -0.1016) (xy -0.2794 -0.1016) (xy -0.2794 0.9906) (xy 0.2794 0.9906)
			)
			(stroke
				(width 0)
				(type default)
			)
			(fill no)
			(layer "B.CrtYd")
		)
		(fp_line
			(start -0.2794 0.9906)
			(end -0.2794 -0.1016)
			(stroke
				(width 0.1)
				(type default)
			)
			(layer "B.Fab")
		)
		(fp_line
			(start 0.2794 0.9906)
			(end -0.2794 0.9906)
			(stroke
				(width 0.1)
				(type default)
			)
			(layer "B.Fab")
		)
		(fp_line
			(start -0.2794 -0.1016)
			(end 0.2794 -0.1016)
			(stroke
				(width 0.1)
				(type default)
			)
			(layer "B.Fab")
		)
		(fp_line
			(start 0.2794 -0.1016)
			(end 0.2794 0.9906)
			(stroke
				(width 0.1)
				(type default)
			)
			(layer "B.Fab")
		)
		(pad "1" smd rect
			(at 0 0 90)
			(size 0.508 0.508)
			(layers "B.Cu" "B.Mask" "B.Paste")
			(net "A_CPU1_GHJ_RCOMP1")
		)
		(pad "2" smd rect
			(at 0 0.889 90)
			(size 0.508 0.508)
			(layers "B.Cu" "B.Mask" "B.Paste")
			(net "GND")
		)
		(zone
			(layer "B.Cu")
			(hatch none 0.5)
			(connect_pads
				(clearance 0)
			)
			(min_thickness 0.25)
			(keepout
				(tracks not_allowed)
				(vias allowed)
				(pads allowed)
				(copperpour not_allowed)
				(footprints allowed)
			)
			(placement
				(enabled no)
				(sheetname "")
			)
			(fill
				(thermal_gap 0.5)
				(thermal_bridge_width 0.5)
				(island_removal_mode 0)
			)
			(polygon
				(pts
					(xy 116.5606 -72.39) (xy 116.5606 -72.898) (xy 116.9416 -72.898) (xy 116.9416 -72.39)
				)
			)
		)
		(zone
			(layer "B.Cu")
			(hatch none 0.5)
			(connect_pads
				(clearance 0)
			)
			(min_thickness 0.25)
			(keepout
				(tracks allowed)
				(vias not_allowed)
				(pads allowed)
				(copperpour not_allowed)
				(footprints allowed)
			)
			(placement
				(enabled no)
				(sheetname "")
			)
			(fill
				(thermal_gap 0.5)
				(thermal_bridge_width 0.5)
				(island_removal_mode 0)
			)
			(polygon
				(pts
					(xy 116.9416 -72.39) (xy 116.9416 -72.898) (xy 116.5606 -72.898) (xy 116.5606 -72.39)
				)
			)
		)
	)
	(footprint ""
		(layer "B.Cu")
		(at 93.105732 -12.888468 -90)
		(property "Reference" "C5G83"
			(at -1.14681 0.76708 0)
			(unlocked yes)
			(layer "B.SilkS")
			(effects
				(font
					(size 0.7874 0.5842)
					(thickness 0.1524)
				)
				(justify mirror)
			)
		)
		(property "Value" ""
			(at 0 0 90)
			(layer "B.Fab")
			(effects
				(font
					(size 1.27 1.27)
				)
				(justify mirror)
			)
		)
		(duplicate_pad_numbers_are_jumpers no)
		(fp_rect
			(start -0.4953 -0.2032)
			(end 0.4953 1.6002)
			(stroke
				(width 0)
				(type default)
			)
			(fill no)
			(layer "B.CrtYd")
		)
		(fp_line
			(start -0.4953 1.6002)
			(end 0.4953 1.6002)
			(stroke
				(width 0.1)
				(type default)
			)
			(layer "B.Fab")
		)
		(fp_line
			(start 0.4953 1.6002)
			(end 0.4953 -0.2032)
			(stroke
				(width 0.1)
				(type default)
			)
			(layer "B.Fab")
		)
		(fp_line
			(start -0.4953 -0.2032)
			(end -0.4953 1.6002)
			(stroke
				(width 0.1)
				(type default)
			)
			(layer "B.Fab")
		)
		(fp_line
			(start 0.4953 -0.2032)
			(end -0.4953 -0.2032)
			(stroke
				(width 0.1)
				(type default)
			)
			(layer "B.Fab")
		)
		(pad "1" smd rect
			(at 0 0 90)
			(size 0.762 0.889)
			(layers "B.Cu" "B.Mask" "B.Paste")
			(net "PVDDQ_GHJ")
		)
		(pad "2" smd rect
			(at 0 1.397 90)
			(size 0.762 0.889)
			(layers "B.Cu" "B.Mask" "B.Paste")
			(net "GND")
		)
		(zone
			(layer "B.Cu")
			(hatch none 0.5)
			(connect_pads
				(clearance 0)
			)
			(min_thickness 0.25)
			(keepout
				(tracks not_allowed)
				(vias allowed)
				(pads allowed)
				(copperpour not_allowed)
				(footprints allowed)
			)
			(placement
				(enabled no)
				(sheetname "")
			)
			(fill
				(thermal_gap 0.5)
				(thermal_bridge_width 0.5)
				(island_removal_mode 0)
			)
			(polygon
				(pts
					(xy 92.661232 -13.269468) (xy 92.153232 -13.269468) (xy 92.153232 -12.507468) (xy 92.661232 -12.507468)
				)
			)
		)
	)
)
